# TIMECARD (Time Appliance Project (Time Card)) — schematic netlist excerpt (pin names and nets, part order shuffled) for the footprints in the layout excerpt that follows; sources: Cadence DE-HDL packaged netlist, KiCad conversion of R4006-B0001-02_R01.brd

R71  RESISTOR  4.7KOHM 1%  pkg SMC_0402R_H016  page 19 : \1\ = XP1R8V_ICP10100 ; \2\ = BF_ICP10100_I2C_SCL
C258  CAPACITOR  0.01UF 25V 10%  pkg SMC_0201R  page 29 : \1\ = SG ; \2\ = XP1R0V_PG

(kicad_pcb
	(version 20260206)
	(generator "pcbnew")
	(generator_version "10.0")
	(general
		(thickness 1.6)
		(legacy_teardrops no)
	)
	(paper "A4")
	(title_block
		(title "timecard-production-celestica-r4006 — R4006-B0001-02_R01.brd")
		(comment 1 "Time Appliance Project (Time Card) / footprints 122-123 of 1113")
	)
	(layers
		(0 "F.Cu" signal "TOP")
		(4 "In1.Cu" signal "L02_GND1")
		(6 "In2.Cu" signal "L03_SIG1")
		(8 "In3.Cu" signal "L04_GND2")
		(10 "In4.Cu" signal "L05_VCC1")
		(12 "In5.Cu" signal "L06_VCC2")
		(14 "In6.Cu" signal "L07_GND3")
		(16 "In7.Cu" signal "L08_SIG2")
		(18 "In8.Cu" signal "L09_GND4")
		(2 "B.Cu" signal "BOTTOM")
		(9 "F.Adhes" user "F.Adhesive")
		(11 "B.Adhes" user "B.Adhesive")
		(13 "F.Paste" user "Package Geometry/Pastemask Top")
		(15 "B.Paste" user "Package Geometry/Pastemask Bottom")
		(5 "F.SilkS" user "Ref Des/Silkscreen Top")
		(7 "B.SilkS" user "Ref Des/Silkscreen Bottom")
		(1 "F.Mask" user "Board Geometry/Soldermask Top")
		(3 "B.Mask" user "Board Geometry/Soldermask Bottom")
		(17 "Dwgs.User" user "User.Drawings")
		(19 "Cmts.User" user "User.Comments")
		(21 "Eco1.User" user "User.Eco1")
		(23 "Eco2.User" user "User.Eco2")
		(25 "Edge.Cuts" user "Board Geometry/Outline")
		(27 "Margin" user)
		(31 "F.CrtYd" user "Package Geometry/Place Bound Top")
		(29 "B.CrtYd" user "Package Geometry/Place Bound Bottom")
		(35 "F.Fab" user "Ref Des/Assembly Top")
		(33 "B.Fab" user "Ref Des/Assembly Bottom")
	)
	(footprint ""
		(layer "F.Cu")
		(at 20.484592 -71.374 90)
		(property "Reference" "R71"
			(at 0.254 1.144778 90)
			(unlocked yes)
			(layer "F.SilkS")
			(effects
				(font
					(size 0.7874 0.5842)
					(thickness 0.1524)
				)
			)
		)
		(property "Value" "VAL*"
			(at 0.02032 2.13233 90)
			(unlocked yes)
			(layer "F.Fab")
			(hide yes)
			(effects
				(font
					(size 0.7874 0.5842)
					(thickness 0.1524)
				)
			)
		)
		(property "Tolerance" "TOL*"
			(at 0.044704 3.05435 90)
			(unlocked yes)
			(layer "Cmts.User")
			(hide yes)
			(effects
				(font
					(size 0.7874 0.5842)
					(thickness 0.1524)
				)
			)
		)
		(property "User Part Number" "PARTNUM*"
			(at 0.02032 4.024884 90)
			(unlocked yes)
			(layer "Cmts.User")
			(hide yes)
			(effects
				(font
					(size 0.7874 0.5842)
					(thickness 0.1524)
				)
			)
		)
		(property "Device Type" "RESISTOR-G155-14701-01,4.7KOHMA"
			(at 0.008382 1.210564 90)
			(unlocked yes)
			(layer "F.Fab")
			(hide yes)
			(effects
				(font
					(size 0.7874 0.5842)
					(thickness 0.1524)
				)
			)
		)
		(duplicate_pad_numbers_are_jumpers no)
		(fp_line
			(start 1.143 -0.5588)
			(end -1.143 -0.5588)
			(stroke
				(width 0.1)
				(type default)
			)
			(layer "F.SilkS")
		)
		(fp_line
			(start -1.143 -0.5588)
			(end -1.143 0.5588)
			(stroke
				(width 0.1)
				(type default)
			)
			(layer "F.SilkS")
		)
		(fp_line
			(start 1.143 0.5588)
			(end 1.143 -0.5588)
			(stroke
				(width 0.1)
				(type default)
			)
			(layer "F.SilkS")
		)
		(fp_line
			(start -1.143 0.5588)
			(end 1.143 0.5588)
			(stroke
				(width 0.1)
				(type default)
			)
			(layer "F.SilkS")
		)
		(fp_rect
			(start 1.143 -0.5588)
			(end -1.143 0.5588)
			(stroke
				(width 0)
				(type default)
			)
			(fill no)
			(layer "F.CrtYd")
		)
		(fp_line
			(start 0.508 -0.3048)
			(end -0.508 -0.3048)
			(stroke
				(width 0.1)
				(type default)
			)
			(layer "F.Fab")
		)
		(fp_line
			(start -0.508 -0.3048)
			(end -0.508 0.3048)
			(stroke
				(width 0.1)
				(type default)
			)
			(layer "F.Fab")
		)
		(fp_line
			(start 0.508 0.3048)
			(end 0.508 -0.3048)
			(stroke
				(width 0.1)
				(type default)
			)
			(layer "F.Fab")
		)
		(fp_line
			(start -0.508 0.3048)
			(end 0.508 0.3048)
			(stroke
				(width 0.1)
				(type default)
			)
			(layer "F.Fab")
		)
		(pad "1" smd rect
			(at -0.5334 0 90)
			(size 0.7112 0.6096)
			(layers "F.Cu" "F.Mask" "F.Paste")
			(net "XP1R8V_ICP10100")
		)
		(pad "2" smd rect
			(at 0.5334 0 90)
			(size 0.7112 0.6096)
			(layers "F.Cu" "F.Mask" "F.Paste")
			(net "BF_ICP10100_I2C_SCL")
		)
		(zone
			(layer "F.Cu")
			(hatch none 0.5)
			(connect_pads
				(clearance 0)
			)
			(min_thickness 0.25)
			(keepout
				(tracks allowed)
				(vias not_allowed)
				(pads allowed)
				(copperpour not_allowed)
				(footprints allowed)
			)
			(placement
				(enabled no)
				(sheetname "")
			)
			(fill
				(thermal_gap 0.5)
				(thermal_bridge_width 0.5)
				(island_removal_mode 0)
			)
			(polygon
				(pts
					(xy 20.179792 -71.4502) (xy 20.179792 -71.2978) (xy 20.789392 -71.2978) (xy 20.789392 -71.4502)
				)
			)
		)
	)
	(footprint ""
		(layer "F.Cu")
		(at 139.954 -59.436 -90)
		(property "Reference" "C258"
			(at -3.175 1.61163 90)
			(unlocked yes)
			(layer "F.SilkS")
			(effects
				(font
					(size 0.7874 0.5842)
					(thickness 0.1524)
				)
			)
		)
		(property "Value" "VAL*"
			(at 0.193548 2.13614 270)
			(unlocked yes)
			(layer "F.Fab")
			(hide yes)
			(effects
				(font
					(size 0.7874 0.5842)
					(thickness 0.1524)
				)
			)
		)
		(property "Tolerance" "TOL*"
			(at 0.216154 3.1496 270)
			(unlocked yes)
			(layer "Cmts.User")
			(hide yes)
			(effects
				(font
					(size 0.7874 0.5842)
					(thickness 0.1524)
				)
			)
		)
		(property "Device Type" "CAPACITOR-G104-0B103-EK,0.01UFA"
			(at 0.184404 1.180592 270)
			(unlocked yes)
			(layer "F.Fab")
			(hide yes)
			(effects
				(font
					(size 0.7874 0.5842)
					(thickness 0.1524)
				)
			)
		)
		(property "User Part Number" "PARTNUM*"
			(at 0.216154 4.185666 270)
			(unlocked yes)
			(layer "Cmts.User")
			(hide yes)
			(effects
				(font
					(size 0.7874 0.5842)
					(thickness 0.1524)
				)
			)
		)
		(duplicate_pad_numbers_are_jumpers no)
		(fp_line
			(start -0.671322 0.4445)
			(end -0.671322 -0.4445)
			(stroke
				(width 0.1)
				(type default)
			)
			(layer "F.SilkS")
		)
		(fp_line
			(start 0.671322 0.4445)
			(end -0.671322 0.4445)
			(stroke
				(width 0.1)
				(type default)
			)
			(layer "F.SilkS")
		)
		(fp_line
			(start -0.671322 -0.4445)
			(end 0.671322 -0.4445)
			(stroke
				(width 0.1)
				(type default)
			)
			(layer "F.SilkS")
		)
		(fp_line
			(start 0.671322 -0.4445)
			(end 0.671322 0.4445)
			(stroke
				(width 0.1)
				(type default)
			)
			(layer "F.SilkS")
		)
		(fp_rect
			(start 0.671322 0.4445)
			(end -0.671322 -0.4445)
			(stroke
				(width 0)
				(type default)
			)
			(fill no)
			(layer "F.CrtYd")
		)
		(fp_line
			(start -0.31496 0.1651)
			(end 0.31496 0.1651)
			(stroke
				(width 0.1)
				(type default)
			)
			(layer "F.Fab")
		)
		(fp_line
			(start 0.31496 0.1651)
			(end 0.31496 -0.1651)
			(stroke
				(width 0.1)
				(type default)
			)
			(layer "F.Fab")
		)
		(fp_line
			(start -0.31496 -0.1651)
			(end -0.31496 0.1651)
			(stroke
				(width 0.1)
				(type default)
			)
			(layer "F.Fab")
		)
		(fp_line
			(start 0.31496 -0.1651)
			(end -0.31496 -0.1651)
			(stroke
				(width 0.1)
				(type default)
			)
			(layer "F.Fab")
		)
		(pad "1" smd rect
			(at -0.264922 0 270)
			(size 0.3048 0.381)
			(layers "F.Cu" "F.Mask" "F.Paste")
			(net "SG")
		)
		(pad "2" smd rect
			(at 0.264922 0 270)
			(size 0.3048 0.381)
			(layers "F.Cu" "F.Mask" "F.Paste")
			(net "XP1R0V_PG")
		)
		(zone
			(layer "F.Cu")
			(hatch none 0.5)
			(connect_pads
				(clearance 0)
			)
			(min_thickness 0.25)
			(keepout
				(tracks allowed)
				(vias not_allowed)
				(pads allowed)
				(copperpour not_allowed)
				(footprints allowed)
			)
			(placement
				(enabled no)
				(sheetname "")
			)
			(fill
				(thermal_gap 0.5)
				(thermal_bridge_width 0.5)
				(island_removal_mode 0)
			)
			(polygon
				(pts
					(xy 139.7635 -59.323478) (xy 140.1445 -59.323478) (xy 140.1445 -59.548522) (xy 139.7635 -59.548522)
				)
			)
		)
	)
)
